(kicad_pcb
	(version 20260206)
	(generator "pcbnew")
	(generator_version "10.0")
	(general
		(thickness 1.6)
		(legacy_teardrops no)
	)
	(paper "A4")
	(title_block
		(title "04192023_DAF0TMB3IC0_F0TG_MB_C_brd_V02_OCP.brd")
		(comment 1 "Grand Teton / footprints 1778-1783 of 8354")
	)
	(layers
		(0 "F.Cu" signal "TOP")
		(4 "In1.Cu" signal "GND")
		(6 "In2.Cu" signal "IN1")
		(8 "In3.Cu" signal "GND1")
		(10 "In4.Cu" signal "IN2")
		(12 "In5.Cu" signal "GND2")
		(14 "In6.Cu" signal "IN3")
		(16 "In7.Cu" signal "GND3")
		(18 "In8.Cu" signal "VCC")
		(20 "In9.Cu" signal "VCC1")
		(22 "In10.Cu" signal "GND4")
		(24 "In11.Cu" signal "IN4")
		(26 "In12.Cu" signal "GND5")
		(28 "In13.Cu" signal "IN5")
		(30 "In14.Cu" signal "GND6")
		(32 "In15.Cu" signal "IN6")
		(34 "In16.Cu" signal "GND7")
		(2 "B.Cu" signal "BOTTOM")
		(9 "F.Adhes" user "F.Adhesive")
		(11 "B.Adhes" user "B.Adhesive")
		(13 "F.Paste" user "Package Geometry/Pastemask Top")
		(15 "B.Paste" user "Package Geometry/Pastemask Bottom")
		(5 "F.SilkS" user "Ref Des/Silkscreen Top")
		(7 "B.SilkS" user "Ref Des/Silkscreen Bottom")
		(1 "F.Mask" user "Board Geometry/Soldermask Top")
		(3 "B.Mask" user "Board Geometry/Soldermask Bottom")
		(17 "Dwgs.User" user "User.Drawings")
		(19 "Cmts.User" user "User.Comments")
		(21 "Eco1.User" user "User.Eco1")
		(23 "Eco2.User" user "User.Eco2")
		(25 "Edge.Cuts" user "Board Geometry/Outline")
		(27 "Margin" user)
		(31 "F.CrtYd" user "Package Geometry/Place Bound Top")
		(29 "B.CrtYd" user "Package Geometry/Place Bound Bottom")
		(35 "F.Fab" user "Ref Des/Assembly Top")
		(33 "B.Fab" user "Ref Des/Assembly Bottom")
	)
	(footprint ""
		(layer "F.Cu")
		(at 142.729712 -75.582272 -0.054)
		(property "Reference" "PR6010"
			(at 0 0 359.946)
			(layer "F.SilkS")
			(hide yes)
			(effects
				(font
					(size 1.27 1.27)
				)
			)
		)
		(property "Value" ""
			(at 0 0 359.946)
			(layer "F.Fab")
			(effects
				(font
					(size 1.27 1.27)
				)
			)
		)
		(duplicate_pad_numbers_are_jumpers no)
		(fp_line
			(start -0.787525 0.40638)
			(end -0.787275 -0.40642)
			(stroke
				(width 0.1524)
				(type default)
			)
			(layer "F.SilkS")
		)
		(fp_line
			(start -0.787275 -0.40642)
			(end 0.787525 -0.40638)
			(stroke
				(width 0.1524)
				(type default)
			)
			(layer "F.SilkS")
		)
		(fp_line
			(start 0.787275 0.40642)
			(end -0.787525 0.40638)
			(stroke
				(width 0.1524)
				(type default)
			)
			(layer "F.SilkS")
		)
		(fp_line
			(start 0.787525 -0.40638)
			(end 0.787275 0.40642)
			(stroke
				(width 0.1524)
				(type default)
			)
			(layer "F.SilkS")
		)
		(fp_line
			(start -0.679417 0.304678)
			(end -0.679484 -0.305176)
			(stroke
				(width 0.1)
				(type default)
			)
			(layer "F.Fab")
		)
		(fp_line
			(start -0.679484 -0.305176)
			(end -0.120683 -0.30494)
			(stroke
				(width 0.1)
				(type default)
			)
			(layer "F.Fab")
		)
		(fp_line
			(start -0.120641 0.279514)
			(end -0.120617 0.304914)
			(stroke
				(width 0.1)
				(type default)
			)
			(layer "F.Fab")
		)
		(fp_line
			(start -0.120617 0.304914)
			(end -0.679417 0.304678)
			(stroke
				(width 0.1)
				(type default)
			)
			(layer "F.Fab")
		)
		(fp_line
			(start -0.120683 -0.30494)
			(end -0.120659 -0.279286)
			(stroke
				(width 0.1)
				(type default)
			)
			(layer "F.Fab")
		)
		(fp_line
			(start -0.120659 -0.279286)
			(end 0.120641 -0.279514)
			(stroke
				(width 0.1)
				(type default)
			)
			(layer "F.Fab")
		)
		(fp_line
			(start 0.120405 0.279287)
			(end -0.120641 0.279514)
			(stroke
				(width 0.1)
				(type default)
			)
			(layer "F.Fab")
		)
		(fp_line
			(start 0.120429 0.304687)
			(end 0.120405 0.279287)
			(stroke
				(width 0.1)
				(type default)
			)
			(layer "F.Fab")
		)
		(fp_line
			(start 0.120617 -0.304914)
			(end 0.679417 -0.304678)
			(stroke
				(width 0.1)
				(type default)
			)
			(layer "F.Fab")
		)
		(fp_line
			(start 0.120641 -0.279514)
			(end 0.120617 -0.304914)
			(stroke
				(width 0.1)
				(type default)
			)
			(layer "F.Fab")
		)
		(fp_line
			(start 0.679484 0.304922)
			(end 0.120429 0.304687)
			(stroke
				(width 0.1)
				(type default)
			)
			(layer "F.Fab")
		)
		(fp_line
			(start 0.679417 -0.304678)
			(end 0.679484 0.304922)
			(stroke
				(width 0.1)
				(type default)
			)
			(layer "F.Fab")
		)
		(pad "1" smd circle
			(at -0.40005 0 359.946)
			(size 0 0)
			(layers "F.Cu" "F.Mask" "F.Paste")
			(net "P1V8_AUX_FB")
		)
		(pad "2" smd circle
			(at 0.40005 0 359.946)
			(size 0 0)
			(layers "F.Cu" "F.Mask" "F.Paste")
			(net "GND")
		)
	)
	(footprint ""
		(layer "F.Cu")
		(at 374.24487 -15.637002)
		(property "Reference" "R1595"
			(at 0 0 0)
			(layer "F.SilkS")
			(hide yes)
			(effects
				(font
					(size 1.27 1.27)
				)
			)
		)
		(property "Value" ""
			(at 0 0 0)
			(layer "F.Fab")
			(effects
				(font
					(size 1.27 1.27)
				)
			)
		)
		(duplicate_pad_numbers_are_jumpers no)
		(fp_line
			(start -0.7874 -0.4064)
			(end 0.7874 -0.4064)
			(stroke
				(width 0.1524)
				(type default)
			)
			(layer "F.SilkS")
		)
		(fp_line
			(start -0.7874 0.4064)
			(end -0.7874 -0.4064)
			(stroke
				(width 0.1524)
				(type default)
			)
			(layer "F.SilkS")
		)
		(fp_line
			(start 0.7874 -0.4064)
			(end 0.7874 0.4064)
			(stroke
				(width 0.1524)
				(type default)
			)
			(layer "F.SilkS")
		)
		(fp_line
			(start 0.7874 0.4064)
			(end -0.7874 0.4064)
			(stroke
				(width 0.1524)
				(type default)
			)
			(layer "F.SilkS")
		)
		(fp_line
			(start -0.67945 -0.305054)
			(end -0.12065 -0.305054)
			(stroke
				(width 0.1)
				(type default)
			)
			(layer "F.Fab")
		)
		(fp_line
			(start -0.67945 0.3048)
			(end -0.67945 -0.305054)
			(stroke
				(width 0.1)
				(type default)
			)
			(layer "F.Fab")
		)
		(fp_line
			(start -0.12065 -0.305054)
			(end -0.12065 -0.2794)
			(stroke
				(width 0.1)
				(type default)
			)
			(layer "F.Fab")
		)
		(fp_line
			(start -0.12065 -0.2794)
			(end 0.12065 -0.2794)
			(stroke
				(width 0.1)
				(type default)
			)
			(layer "F.Fab")
		)
		(fp_line
			(start -0.12065 0.2794)
			(end -0.12065 0.3048)
			(stroke
				(width 0.1)
				(type default)
			)
			(layer "F.Fab")
		)
		(fp_line
			(start -0.12065 0.3048)
			(end -0.67945 0.3048)
			(stroke
				(width 0.1)
				(type default)
			)
			(layer "F.Fab")
		)
		(fp_line
			(start 0.120396 0.2794)
			(end -0.12065 0.2794)
			(stroke
				(width 0.1)
				(type default)
			)
			(layer "F.Fab")
		)
		(fp_line
			(start 0.120396 0.3048)
			(end 0.120396 0.2794)
			(stroke
				(width 0.1)
				(type default)
			)
			(layer "F.Fab")
		)
		(fp_line
			(start 0.12065 -0.3048)
			(end 0.67945 -0.3048)
			(stroke
				(width 0.1)
				(type default)
			)
			(layer "F.Fab")
		)
		(fp_line
			(start 0.12065 -0.2794)
			(end 0.12065 -0.3048)
			(stroke
				(width 0.1)
				(type default)
			)
			(layer "F.Fab")
		)
		(fp_line
			(start 0.67945 -0.3048)
			(end 0.67945 0.3048)
			(stroke
				(width 0.1)
				(type default)
			)
			(layer "F.Fab")
		)
		(fp_line
			(start 0.67945 0.3048)
			(end 0.120396 0.3048)
			(stroke
				(width 0.1)
				(type default)
			)
			(layer "F.Fab")
		)
		(pad "1" smd circle
			(at -0.40005 0)
			(size 0 0)
			(layers "F.Cu" "F.Mask" "F.Paste")
			(net "OCP_SFF_PWRBRK_BUFF_N")
		)
		(pad "2" smd circle
			(at 0.40005 0)
			(size 0 0)
			(layers "F.Cu" "F.Mask" "F.Paste")
			(net "OCP_SFF_PWRBRK_N")
		)
	)
	(footprint ""
		(layer "F.Cu")
		(at 304.419 -361.696)
		(property "Reference" "R8063"
			(at 0 0 0)
			(layer "F.SilkS")
			(hide yes)
			(effects
				(font
					(size 1.27 1.27)
				)
			)
		)
		(property "Value" ""
			(at 0 0 0)
			(layer "F.Fab")
			(effects
				(font
					(size 1.27 1.27)
				)
			)
		)
		(duplicate_pad_numbers_are_jumpers no)
		(fp_line
			(start -0.7874 -0.4064)
			(end 0.7874 -0.4064)
			(stroke
				(width 0.1524)
				(type default)
			)
			(layer "F.SilkS")
		)
		(fp_line
			(start -0.7874 0.4064)
			(end -0.7874 -0.4064)
			(stroke
				(width 0.1524)
				(type default)
			)
			(layer "F.SilkS")
		)
		(fp_line
			(start 0.7874 -0.4064)
			(end 0.7874 0.4064)
			(stroke
				(width 0.1524)
				(type default)
			)
			(layer "F.SilkS")
		)
		(fp_line
			(start 0.7874 0.4064)
			(end -0.7874 0.4064)
			(stroke
				(width 0.1524)
				(type default)
			)
			(layer "F.SilkS")
		)
		(fp_line
			(start -0.67945 -0.305054)
			(end -0.12065 -0.305054)
			(stroke
				(width 0.1)
				(type default)
			)
			(layer "F.Fab")
		)
		(fp_line
			(start -0.67945 0.3048)
			(end -0.67945 -0.305054)
			(stroke
				(width 0.1)
				(type default)
			)
			(layer "F.Fab")
		)
		(fp_line
			(start -0.12065 -0.305054)
			(end -0.12065 -0.2794)
			(stroke
				(width 0.1)
				(type default)
			)
			(layer "F.Fab")
		)
		(fp_line
			(start -0.12065 -0.2794)
			(end 0.12065 -0.2794)
			(stroke
				(width 0.1)
				(type default)
			)
			(layer "F.Fab")
		)
		(fp_line
			(start -0.12065 0.2794)
			(end -0.12065 0.3048)
			(stroke
				(width 0.1)
				(type default)
			)
			(layer "F.Fab")
		)
		(fp_line
			(start -0.12065 0.3048)
			(end -0.67945 0.3048)
			(stroke
				(width 0.1)
				(type default)
			)
			(layer "F.Fab")
		)
		(fp_line
			(start 0.120396 0.2794)
			(end -0.12065 0.2794)
			(stroke
				(width 0.1)
				(type default)
			)
			(layer "F.Fab")
		)
		(fp_line
			(start 0.120396 0.3048)
			(end 0.120396 0.2794)
			(stroke
				(width 0.1)
				(type default)
			)
			(layer "F.Fab")
		)
		(fp_line
			(start 0.12065 -0.3048)
			(end 0.67945 -0.3048)
			(stroke
				(width 0.1)
				(type default)
			)
			(layer "F.Fab")
		)
		(fp_line
			(start 0.12065 -0.2794)
			(end 0.12065 -0.3048)
			(stroke
				(width 0.1)
				(type default)
			)
			(layer "F.Fab")
		)
		(fp_line
			(start 0.67945 -0.3048)
			(end 0.67945 0.3048)
			(stroke
				(width 0.1)
				(type default)
			)
			(layer "F.Fab")
		)
		(fp_line
			(start 0.67945 0.3048)
			(end 0.120396 0.3048)
			(stroke
				(width 0.1)
				(type default)
			)
			(layer "F.Fab")
		)
		(pad "1" smd circle
			(at -0.40005 0)
			(size 0 0)
			(layers "F.Cu" "F.Mask" "F.Paste")
			(net "PVDDCR_CPU1_P0_RESET_N")
		)
		(pad "2" smd circle
			(at 0.40005 0)
			(size 0 0)
			(layers "F.Cu" "F.Mask" "F.Paste")
			(net "PVDDCR_CPU1_P0_RESET_N_R")
		)
	)
	(footprint ""
		(layer "F.Cu")
		(at 281.686 -423.418 -90)
		(property "Reference" "R4476"
			(at 0 0 270)
			(layer "F.SilkS")
			(hide yes)
			(effects
				(font
					(size 1.27 1.27)
				)
			)
		)
		(property "Value" ""
			(at 0 0 270)
			(layer "F.Fab")
			(effects
				(font
					(size 1.27 1.27)
				)
			)
		)
		(duplicate_pad_numbers_are_jumpers no)
		(fp_line
			(start -0.7874 0.4064)
			(end -0.7874 -0.4064)
			(stroke
				(width 0.1524)
				(type default)
			)
			(layer "F.SilkS")
		)
		(fp_line
			(start 0.7874 0.4064)
			(end -0.7874 0.4064)
			(stroke
				(width 0.1524)
				(type default)
			)
			(layer "F.SilkS")
		)
		(fp_line
			(start -0.7874 -0.4064)
			(end 0.7874 -0.4064)
			(stroke
				(width 0.1524)
				(type default)
			)
			(layer "F.SilkS")
		)
		(fp_line
			(start 0.7874 -0.4064)
			(end 0.7874 0.4064)
			(stroke
				(width 0.1524)
				(type default)
			)
			(layer "F.SilkS")
		)
		(fp_line
			(start -0.67945 0.3048)
			(end -0.67945 -0.305054)
			(stroke
				(width 0.1)
				(type default)
			)
			(layer "F.Fab")
		)
		(fp_line
			(start -0.12065 0.3048)
			(end -0.67945 0.3048)
			(stroke
				(width 0.1)
				(type default)
			)
			(layer "F.Fab")
		)
		(fp_line
			(start 0.120396 0.3048)
			(end 0.120396 0.2794)
			(stroke
				(width 0.1)
				(type default)
			)
			(layer "F.Fab")
		)
		(fp_line
			(start 0.67945 0.3048)
			(end 0.120396 0.3048)
			(stroke
				(width 0.1)
				(type default)
			)
			(layer "F.Fab")
		)
		(fp_line
			(start -0.12065 0.2794)
			(end -0.12065 0.3048)
			(stroke
				(width 0.1)
				(type default)
			)
			(layer "F.Fab")
		)
		(fp_line
			(start 0.120396 0.2794)
			(end -0.12065 0.2794)
			(stroke
				(width 0.1)
				(type default)
			)
			(layer "F.Fab")
		)
		(fp_line
			(start -0.12065 -0.2794)
			(end 0.12065 -0.2794)
			(stroke
				(width 0.1)
				(type default)
			)
			(layer "F.Fab")
		)
		(fp_line
			(start 0.12065 -0.2794)
			(end 0.12065 -0.3048)
			(stroke
				(width 0.1)
				(type default)
			)
			(layer "F.Fab")
		)
		(fp_line
			(start 0.12065 -0.3048)
			(end 0.67945 -0.3048)
			(stroke
				(width 0.1)
				(type default)
			)
			(layer "F.Fab")
		)
		(fp_line
			(start 0.67945 -0.3048)
			(end 0.67945 0.3048)
			(stroke
				(width 0.1)
				(type default)
			)
			(layer "F.Fab")
		)
		(fp_line
			(start -0.67945 -0.305054)
			(end -0.12065 -0.305054)
			(stroke
				(width 0.1)
				(type default)
			)
			(layer "F.Fab")
		)
		(fp_line
			(start -0.12065 -0.305054)
			(end -0.12065 -0.2794)
			(stroke
				(width 0.1)
				(type default)
			)
			(layer "F.Fab")
		)
		(pad "1" smd circle
			(at -0.40005 0 270)
			(size 0 0)
			(layers "F.Cu" "F.Mask" "F.Paste")
			(net "P3V3_AUX")
		)
		(pad "2" smd circle
			(at 0.40005 0 270)
			(size 0 0)
			(layers "F.Cu" "F.Mask" "F.Paste")
			(net "FM_9ZXL045_P0_DEV_EN")
		)
	)
	(footprint ""
		(layer "F.Cu")
		(at 271.739106 -346.714572 -90)
		(property "Reference" "PC173_IOP0_4"
			(at 0 0 270)
			(layer "F.SilkS")
			(hide yes)
			(effects
				(font
					(size 1.27 1.27)
				)
			)
		)
		(property "Value" ""
			(at 0 0 270)
			(layer "F.Fab")
			(effects
				(font
					(size 1.27 1.27)
				)
			)
		)
		(duplicate_pad_numbers_are_jumpers no)
		(fp_line
			(start -0.7874 0.4064)
			(end -0.7874 -0.4064)
			(stroke
				(width 0.1524)
				(type default)
			)
			(layer "F.SilkS")
		)
		(fp_line
			(start 0.7874 0.4064)
			(end -0.7874 0.4064)
			(stroke
				(width 0.1524)
				(type default)
			)
			(layer "F.SilkS")
		)
		(fp_line
			(start -0.7874 -0.4064)
			(end 0.7874 -0.4064)
			(stroke
				(width 0.1524)
				(type default)
			)
			(layer "F.SilkS")
		)
		(fp_line
			(start 0.7874 -0.4064)
			(end 0.7874 0.4064)
			(stroke
				(width 0.1524)
				(type default)
			)
			(layer "F.SilkS")
		)
		(fp_line
			(start -0.67945 0.3048)
			(end -0.67945 -0.305054)
			(stroke
				(width 0.1)
				(type default)
			)
			(layer "F.Fab")
		)
		(fp_line
			(start -0.12065 0.3048)
			(end -0.67945 0.3048)
			(stroke
				(width 0.1)
				(type default)
			)
			(layer "F.Fab")
		)
		(fp_line
			(start 0.120396 0.3048)
			(end 0.120396 0.2794)
			(stroke
				(width 0.1)
				(type default)
			)
			(layer "F.Fab")
		)
		(fp_line
			(start 0.67945 0.3048)
			(end 0.120396 0.3048)
			(stroke
				(width 0.1)
				(type default)
			)
			(layer "F.Fab")
		)
		(fp_line
			(start -0.12065 0.2794)
			(end -0.12065 0.3048)
			(stroke
				(width 0.1)
				(type default)
			)
			(layer "F.Fab")
		)
		(fp_line
			(start 0.120396 0.2794)
			(end -0.12065 0.2794)
			(stroke
				(width 0.1)
				(type default)
			)
			(layer "F.Fab")
		)
		(fp_line
			(start -0.12065 -0.2794)
			(end 0.12065 -0.2794)
			(stroke
				(width 0.1)
				(type default)
			)
			(layer "F.Fab")
		)
		(fp_line
			(start 0.12065 -0.2794)
			(end 0.12065 -0.3048)
			(stroke
				(width 0.1)
				(type default)
			)
			(layer "F.Fab")
		)
		(fp_line
			(start 0.12065 -0.3048)
			(end 0.67945 -0.3048)
			(stroke
				(width 0.1)
				(type default)
			)
			(layer "F.Fab")
		)
		(fp_line
			(start 0.67945 -0.3048)
			(end 0.67945 0.3048)
			(stroke
				(width 0.1)
				(type default)
			)
			(layer "F.Fab")
		)
		(fp_line
			(start -0.67945 -0.305054)
			(end -0.12065 -0.305054)
			(stroke
				(width 0.1)
				(type default)
			)
			(layer "F.Fab")
		)
		(fp_line
			(start -0.12065 -0.305054)
			(end -0.12065 -0.2794)
			(stroke
				(width 0.1)
				(type default)
			)
			(layer "F.Fab")
		)
		(pad "1" smd circle
			(at -0.40005 0 270)
			(size 0 0)
			(layers "F.Cu" "F.Mask" "F.Paste")
			(net "PVDDCR_CPU1_P0_PVCC")
		)
		(pad "2" smd circle
			(at 0.40005 0 270)
			(size 0 0)
			(layers "F.Cu" "F.Mask" "F.Paste")
			(net "GND")
		)
	)
	(footprint ""
		(layer "F.Cu")
		(at 65.3796 -13.8176 180)
		(property "Reference" "C1832"
			(at 0 0 180)
			(layer "F.SilkS")
			(hide yes)
			(effects
				(font
					(size 1.27 1.27)
				)
			)
		)
		(property "Value" ""
			(at 0 0 180)
			(layer "F.Fab")
			(effects
				(font
					(size 1.27 1.27)
				)
			)
		)
		(duplicate_pad_numbers_are_jumpers no)
		(fp_line
			(start 0.7874 0.4064)
			(end -0.7874 0.4064)
			(stroke
				(width 0.1524)
				(type default)
			)
			(layer "F.SilkS")
		)
		(fp_line
			(start 0.7874 -0.4064)
			(end 0.7874 0.4064)
			(stroke
				(width 0.1524)
				(type default)
			)
			(layer "F.SilkS")
		)
		(fp_line
			(start -0.7874 0.4064)
			(end -0.7874 -0.4064)
			(stroke
				(width 0.1524)
				(type default)
			)
			(layer "F.SilkS")
		)
		(fp_line
			(start -0.7874 -0.4064)
			(end 0.7874 -0.4064)
			(stroke
				(width 0.1524)
				(type default)
			)
			(layer "F.SilkS")
		)
		(fp_line
			(start 0.67945 0.3048)
			(end 0.120396 0.3048)
			(stroke
				(width 0.1)
				(type default)
			)
			(layer "F.Fab")
		)
		(fp_line
			(start 0.67945 -0.3048)
			(end 0.67945 0.3048)
			(stroke
				(width 0.1)
				(type default)
			)
			(layer "F.Fab")
		)
		(fp_line
			(start 0.12065 -0.2794)
			(end 0.12065 -0.3048)
			(stroke
				(width 0.1)
				(type default)
			)
			(layer "F.Fab")
		)
		(fp_line
			(start 0.12065 -0.3048)
			(end 0.67945 -0.3048)
			(stroke
				(width 0.1)
				(type default)
			)
			(layer "F.Fab")
		)
		(fp_line
			(start 0.120396 0.3048)
			(end 0.120396 0.2794)
			(stroke
				(width 0.1)
				(type default)
			)
			(layer "F.Fab")
		)
		(fp_line
			(start 0.120396 0.2794)
			(end -0.12065 0.2794)
			(stroke
				(width 0.1)
				(type default)
			)
			(layer "F.Fab")
		)
		(fp_line
			(start -0.12065 0.3048)
			(end -0.67945 0.3048)
			(stroke
				(width 0.1)
				(type default)
			)
			(layer "F.Fab")
		)
		(fp_line
			(start -0.12065 0.2794)
			(end -0.12065 0.3048)
			(stroke
				(width 0.1)
				(type default)
			)
			(layer "F.Fab")
		)
		(fp_line
			(start -0.12065 -0.2794)
			(end 0.12065 -0.2794)
			(stroke
				(width 0.1)
				(type default)
			)
			(layer "F.Fab")
		)
		(fp_line
			(start -0.12065 -0.305054)
			(end -0.12065 -0.2794)
			(stroke
				(width 0.1)
				(type default)
			)
			(layer "F.Fab")
		)
		(fp_line
			(start -0.67945 0.3048)
			(end -0.67945 -0.305054)
			(stroke
				(width 0.1)
				(type default)
			)
			(layer "F.Fab")
		)
		(fp_line
			(start -0.67945 -0.305054)
			(end -0.12065 -0.305054)
			(stroke
				(width 0.1)
				(type default)
			)
			(layer "F.Fab")
		)
		(pad "1" smd circle
			(at -0.40005 0 180)
			(size 0 0)
			(layers "F.Cu" "F.Mask" "F.Paste")
			(net "P12V_OCP_V3_2_R")
		)
		(pad "2" smd circle
			(at 0.40005 0 180)
			(size 0 0)
			(layers "F.Cu" "F.Mask" "F.Paste")
			(net "GND")
		)
	)
)
